FILE_TYPE = MULTI_PHYS_TABLE;

PART 'Q_SP_RES4P'

{========================================================================================}
:VALUE     | TOLERANCE | WATTAGE | PART_TYPE | MATERIAL | PART_NUMBER        = STANDARD        | LIFECYCLE          | PART_NUMBER   | JEDEC_TYPE         | DESCRIPTION                                   | MANUFTR | MANUF_PN              | RD_CMPLS_LVL | CMPLS_LVL | CLASS      | DIP_SMD | FROM_PJ         | DATA                                    | FP_ECN                     | EE_CHECK_LIST  | PSL | PREFERENCE | CREATOR | STATUS | CREATEDAY    ;
{========================================================================================}
 '0.002'   | '1%'      | '2W'    | 'SMLF'    | 'CHIP'   | 'SP_CS+002AFR00'(!) = ''              | ''                 | 'CS+002AFR00' |'R2512_4PXF'| 'RES CHIP 0.002 2W +-1%(2512)'                | 'WTC'   | 'WW25NR002FTL'        | ''           | 'EP_Tmp'  | 'DISCRETE' | ''      | 'T96-JAMES'     | 'WTC_WW25N_R2512_4P.pdf'                | ''                         | 'R2512_4P.xls' | ''  | ''         | ''      | ''     | '20120214'  
 '0.002'   | '1%'      | '2W'    | 'SMLF'    | 'EMPTY'  | 'SP_CS+002AFR00'(!) = ''              | ''                 | 'CS+002AFR00' |'R2512_4PXF'| 'RES CHIP 0.002 2W +-1%(2512)'                | 'WTC'   | 'WW25NR002FTL'        | ''           | 'EP_Tmp'  | 'DISCRETE' | ''      | 'T96-JAMES'     | 'WTC_WW25N_R2512_4P.pdf'                | ''                         | 'R2512_4P.xls' | ''  | ''         | ''      | ''     | '20120214'  
 '0.003'   | '1%'      | '1W'    | 'SMLF'    | 'CHIP'   | 'SP_CS+0038F128'(!) = 'End of Design' | 'Comp-Approve'     | 'CS+0038F128' |'R2512_4PXF'| 'RES CHIP 0.003 1W +-1%(2512)'                | 'YGO'   | 'PR2512FKF070R003L'   | ''           | 'EP'      | 'DISCRETE' | ''      | 'S95-DONALD'    | 'YGO_LF_RES SERIES.pdf'                 | 'R2512_4PXF.pdf'           | ''             | ''  | ''         | ''      | ''     | '20120214'  
 '0.003'   | '1%'      | '1W'    | 'SMLF'    | 'EMPTY'  | 'SP_CS+0038F128'(!) = 'End of Design' | 'Comp-Approve'     | 'CS+0038F128' |'R2512_4PXF'| 'RES CHIP 0.003 1W +-1%(2512)'                | 'YGO'   | 'PR2512FKF070R003L'   | ''           | 'EP'      | 'DISCRETE' | ''      | 'S95-DONALD'    | 'YGO_LF_RES SERIES.pdf'                 | 'R2512_4PXF.pdf'           | ''             | ''  | ''         | ''      | ''     | '20120214'  
 '0.009'   | '1%'      | '1W'    | 'SMLF'    | 'CHIP'   | 'SP_CS00008FR00'(!) = ''              | ''                 | 'CS00008FR00' |'R2512_4PXG'| 'RES CHIP 0.009 1W +-1%(2512)H0.787'          | 'RLC'   | 'LR2512-21R009F2'     | 'EP(V1)'     | ''        | 'DISCRETE' | ''      | 'T2L-CHEESE'    | 'LR-SERIES_20111019.pdf'                | 'R2512_4PXF.pdf'           | ''             | ''  | ''         | ''      | ''     | '20120216'  
 '0.009'   | '1%'      | '1W'    | 'SMLF'    | 'EMPTY'  | 'SP_CS00008FR00'(!) = ''              | ''                 | 'CS00008FR00' |'R2512_4PXG'| 'RES CHIP 0.009 1W +-1%(2512)H0.787'          | 'RLC'   | 'LR2512-21R009F2'     | 'EP(V1)'     | ''        | 'DISCRETE' | ''      | 'T2L-CHEESE'    | 'LR-SERIES_20111019.pdf'                | 'R2512_4PXF.pdf'           | ''             | ''  | ''         | ''      | ''     | '20120216'  
 '0.005'   | '1%'      | '1W'    | 'SMLF'    | 'CHIP'   | 'SP_CS+0058F127'(!) = ''              | ''                 | 'CS+0058F127' |'R2512_4PXG'| 'RES CHIP 0.005 1W +-1%(2512)'                | 'YGO'   | 'PR2512FKF070R005L'   | ''           | 'EP'      | 'DISCRETE' | ''      | 'RS2-EASON'     | 'YGO_LF_RES SERIES.pdf'                 | 'R2512.doc'                | ''             | ''  | ''         | ''      | ''     | '20120228'  
 '0.005'   | '1%'      | '1W'    | 'SMLF'    | 'EMPTY'  | 'SP_CS+0058F127'(!) = ''              | ''                 | 'CS+0058F127' |'R2512_4PXG'| 'RES CHIP 0.005 1W +-1%(2512)'                | 'YGO'   | 'PR2512FKF070R005L'   | ''           | 'EP'      | 'DISCRETE' | ''      | 'RS2-EASON'     | 'YGO_LF_RES SERIES.pdf'                 | 'R2512.doc'                | ''             | ''  | ''         | ''      | ''     | '20120228'  
 '0.004'   | '1%'      | '1W'    | 'SMLF'    | 'CHIP'   | 'SP_CS+0048F200'(!) = ''              | ''                 | 'CS+0048F200' |'R1206XA_4P'| 'RES CHIP 0.004 1W +-1%(1206)'                | 'RLC'   | 'LR06-21R004FTE'      | 'EP(V1)'     | 'EP(V1)'  | 'DISCRETE' | ''      | 'S2S-WIN'       | 'LR-SERIES_REV2010-02-03.pdf'           | ''                         | ''             | ''  | ''         | ''      | ''     | '2012/10/31'
 '0.004'   | '1%'      | '1W'    | 'SMLF'    | 'EMPTY'  | 'SP_CS+0048F200'(!) = ''              | ''                 | 'CS+0048F200' |'R1206XA_4P'| 'RES CHIP 0.004 1W +-1%(1206)'                | 'RLC'   | 'LR06-21R004FTE'      | 'EP(V1)'     | 'EP(V1)'  | 'DISCRETE' | ''      | 'S2S-WIN'       | 'LR-SERIES_REV2010-02-03.pdf'           | ''                         | ''             | ''  | ''         | ''      | ''     | '2012/10/31'
 '0.00025' | '1%'      | '4W'    | 'SMLF'    | 'CHIP'   | 'SP_CS0000FFT00'(!) = 'End of Design' | 'Comp-Approve'     | 'CS0000FFT00' |'R2725_4P'| 'RES CHIP 0.00025 4W +-1%(2725)H0.991'        | 'RLC'   | 'LR2725-24R00025F1'   | 'EP(V1)'     | ''        | 'DISCRETE' | ''      | 'F06-KOOL'      | 'LR-series_rev20111019.pdf'             | ''                         | ''             | ''  | ''         | ''      | ''     | '20130501'  
 '0.00025' | '1%'      | '4W'    | 'SMLF'    | 'EMPTY'  | 'SP_CS0000FFT00'(!) = 'End of Design' | 'Comp-Approve'     | 'CS0000FFT00' |'R2725_4P'| 'RES CHIP 0.00025 4W +-1%(2725)H0.991'        | 'RLC'   | 'LR2725-24R00025F1'   | 'EP(V1)'     | ''        | 'DISCRETE' | ''      | 'F06-KOOL'      | 'LR-series_rev20111019.pdf'             | ''                         | ''             | ''  | ''         | ''      | ''     | '20130501'  
 '0.0002'  | '1%'      | '4W'    | 'SMLF'    | 'CHIP'   | 'SP_CS0000FFT01_1'(!) = ''              | ''                 | 'CS0000FFT01' |'R2725_4P'| 'RES CHIP 0.0002 4W +-1%(2725)H1.131_PIN CUT' | 'RLC'   | 'LR2725-24R0002F1'    | 'EP(V1)'     | ''        | 'DISCRETE' | ''      | 'TU1H-LIN-HAN'  | 'LR-SERIES_REV2013-04-03.pdf'           | 'R2725_4P.msg'             | ''             | ''  | ''         | ''      | ''     | '20131213'  
 '0.0002'  | '1%'      | '4W'    | 'SMLF'    | 'EMPTY'  | 'SP_CS0000FFT01_1'(!) = ''              | ''                 | 'CS0000FFT01' |'R2725_4P'| 'RES CHIP 0.0002 4W +-1%(2725)H1.131_PIN CUT' | 'RLC'   | 'LR2725-24R0002F1'    | 'EP(V1)'     | ''        | 'DISCRETE' | ''      | 'TU1H-LIN-HAN'  | 'LR-SERIES_REV2013-04-03.pdf'           | 'R2725_4P.msg'             | ''             | ''  | ''         | ''      | ''     | '20131213'  
 '0.001'   | '1%'      | '1W'    | 'SMLF'    | 'CHIP'   | 'SP_CS+0018FL00'(!) = ''              | ''                 | 'CS+0018FL00' |'R3720_4P'| 'RES CHIP 0.001 1W +-1%(3720)'                | 'CYN'   | 'RL3720WT-R001-FN'    | 'EP(V1)'     | 'EP(V1)'  | 'DISCRETE' | ''      | 'F07-KC'        | 'CYN_RL SERIES_revB0.pdf'               | ''                         | ''             | ''  | ''         | ''      | ''     | '20140811'  
 '0.001'   | '1%'      | '1W'    | 'SMLF'    | 'EMPTY'  | 'SP_CS+0018FL00'(!) = ''              | ''                 | 'CS+0018FL00' |'R3720_4P'| 'RES CHIP 0.001 1W +-1%(3720)'                | 'CYN'   | 'RL3720WT-R001-FN'    | 'EP(V1)'     | 'EP(V1)'  | 'DISCRETE' | ''      | 'F07-KC'        | 'CYN_RL SERIES_revB0.pdf'               | ''                         | ''             | ''  | ''         | ''      | ''     | '20140811'  
 '0.003'   | '1%'      | '1W'    | 'SMLF'    | 'CHIP'   | 'SP_CS+0038FL00'(!) = ''              | ''                 | 'CS+0038FL00' |'R3720XA_4P'| 'RES CHIP 0.003 1W +-1% (3720)'               | 'CYN'   | 'RL3720WT-R003-FN'    | 'EP(V1)'     | ''        | 'DISCRETE' | ''      | 'F07-KC'        | 'CYN_RL3720WT_REV2.pdf'                 | ''                         | ''             | ''  | ''         | ''      | ''     | '20140814'  
 '0.003'   | '1%'      | '1W'    | 'SMLF'    | 'EMPTY'  | 'SP_CS+0038FL00'(!) = ''              | ''                 | 'CS+0038FL00' |'R3720XA_4P'| 'RES CHIP 0.003 1W +-1% (3720)'               | 'CYN'   | 'RL3720WT-R003-FN'    | 'EP(V1)'     | ''        | 'DISCRETE' | ''      | 'F07-KC'        | 'CYN_RL3720WT_REV2.pdf'                 | ''                         | ''             | ''  | ''         | ''      | ''     | '20140814'  
 '0.007'   | '1%'      | '1W'    | 'SMLF'    | 'CHIP'   | 'SP_CS+0078FL00'(!) = 'End of Design' | 'Comp-Approve'     | 'CS+0078FL00' |'R3720XA_4P'| 'RES CHIP 0.007 1W +-1%(3720)'                | 'CYN'   | 'RL3720WT-R007-FN'    | 'EP(V1)'     | ''        | 'DISCRETE' | ''      | 'F07-KC'        | 'CYN_RL3720WT_REV2.pdf'                 | ''                         | ''             | ''  | ''         | ''      | ''     | '20140817'  
 '0.007'   | '1%'      | '1W'    | 'SMLF'    | 'EMPTY'  | 'SP_CS+0078FL00'(!) = 'End of Design' | 'Comp-Approve'     | 'CS+0078FL00' |'R3720XA_4P'| 'RES CHIP 0.007 1W +-1%(3720)'                | 'CYN'   | 'RL3720WT-R007-FN'    | 'EP(V1)'     | ''        | 'DISCRETE' | ''      | 'F07-KC'        | 'CYN_RL3720WT_REV2.pdf'                 | ''                         | ''             | ''  | ''         | ''      | ''     | '20140817'  
 '0.001'   | '1%'      | '3W'    | 'SMLF'    | 'CHIP'   | 'SP_CS0000DFR01_1'(!) = 'Potential'     | 'End of Life'      | 'CS0000DFR01' |'R2512_4PXH_EOL'| 'RES CHIP 0.001 3W(+-1%,2512)'                | 'RLC'   | 'LR25-23R001FE6'      | 'EP(V1)'     | ''        | 'DISCRETE' | ''      | 'S5A-AARON'     | 'RLC_LR SERIES.pdf'                     | ''                         | ''             | ''  | ''         | ''      | ''     | '20150107'  
 '0.001'   | '1%'      | '3W'    | 'SMLF'    | 'EMPTY'  | 'SP_CS0000DFR01_1'(!) = 'Potential'     | 'End of Life'      | 'CS0000DFR01' |'R2512_4PXH_EOL'| 'RES CHIP 0.001 3W(+-1%,2512)'                | 'RLC'   | 'LR25-23R001FE6'      | 'EP(V1)'     | ''        | 'DISCRETE' | ''      | 'S5A-AARON'     | 'RLC_LR SERIES.pdf'                     | ''                         | ''             | ''  | ''         | ''      | ''     | '20150107'  
 '0.0005'  | '1%'      | '3W'    | 'SMLF'    | 'CHIP'   | 'SP_CS0000DFR00_1'(!) = ''              | ''                 | 'CS0000DFR00' |'R2512A_4P'| 'RES CHIP 0.0005 3W +-1%(2512)'               | 'RLC'   | 'LR25-23R001FE6'      | 'EP(V1)'     | ''        | 'DISCRETE' | ''      | 'S2PC-JOSHUA'   | 'LR-series.pdf'                         | ''                         | ''             | ''  | ''         | ''      | ''     | '20150123'  
 '0.0005'  | '1%'      | '3W'    | 'SMLF'    | 'EMPTY'  | 'SP_CS0000DFR00_1'(!) = ''              | ''                 | 'CS0000DFR00' |'R2512A_4P'| 'RES CHIP 0.0005 3W +-1%(2512)'               | 'RLC'   | 'LR25-23R001FE6'      | 'EP(V1)'     | ''        | 'DISCRETE' | ''      | 'S2PC-JOSHUA'   | 'LR-series.pdf'                         | ''                         | ''             | ''  | ''         | ''      | ''     | '20150123'  
 '0.004'   | '1%'      | '3W'    | 'SMLF'    | 'CHIP'   | 'SP_CS+004DFR00_1'(!) = ''              | ''                 | 'CS+004DFR00' |'R2512_4PXF'| 'RES CHIP 0.004 3W +-1%(2512)'                | 'TAI'   | 'RLP25FEGR004'        | 'EP(V1)'     | ''        | 'DISCRETE' | ''      | 'T2H-HSUEH-YEN' | 'LR-series.pdf'                         | ''                         | ''             | ''  | ''         | ''      | ''     | '20150713'  
 '0.004'   | '1%'      | '3W'    | 'SMLF'    | 'EMPTY'  | 'SP_CS+004DFR00_1'(!) = ''              | ''                 | 'CS+004DFR00' |'R2512_4PXF'| 'RES CHIP 0.004 3W +-1%(2512)'                | 'TAI'   | 'RLP25FEGR004'        | 'EP(V1)'     | ''        | 'DISCRETE' | ''      | 'T2H-HSUEH-YEN' | 'LR-series.pdf'                         | ''                         | ''             | ''  | ''         | ''      | ''     | '20150713'  
 '0.002'   | '1%'      | '3W'    | 'SMLF'    | 'CHIP'   | 'SP_CS+002DFR00_1'(!) = ''              | ''                 | 'CS+002DFR00' |'R2512_4PXN'| 'RES CHIP 0.002 3W +-1%(2512)'                | 'RLC'   | 'LR2512-23R002F4'     | 'EP(V1)'     | 'EP(V1)'  | 'DISCRETE' | ''      | 'S5B-JEFF'      | 'RLC_LR2512-23R002F4.pdf'               | ''                         | ''             | ''  | ''         | ''      | ''     | '20150910'  
 '0.002'   | '1%'      | '3W'    | 'SMLF'    | 'EMPTY'  | 'SP_CS+002DFR00_1'(!) = ''              | ''                 | 'CS+002DFR00' |'R2512_4PXN'| 'RES CHIP 0.002 3W +-1%(2512)'                | 'RLC'   | 'LR2512-23R002F4'     | 'EP(V1)'     | 'EP(V1)'  | 'DISCRETE' | ''      | 'S5B-JEFF'      | 'RLC_LR2512-23R002F4.pdf'               | ''                         | ''             | ''  | ''         | ''      | ''     | '20150910'  
 '0.0005'  | '1%'      | '1W'    | 'SMLF'    | 'CHIP'   | 'CS00008F200'(!)   = 'End of Design' | 'Comp-Release Qty' | 'CS00008F200' |'R1206_4P'| 'RES CHIP 0.0005 1W +-1%(1206)'               | 'CYN'   | 'RL1632T4F-0R5M-FN'   | 'EP(V1)'     | ''        | 'DISCRETE' | ''      | 'S5B-JEFF'      | 'CYN_RL1632T4F-0R5M-FN.pdf'             | ''                         | ''             | ''  | ''         | ''      | ''     | '20150930'  
 '0.0005'  | '1%'      | '1W'    | 'SMLF'    | 'EMPTY'  | 'CS00008F200'(!)   = 'End of Design' | 'Comp-Release Qty' | 'CS00008F200' |'R1206_4P'| 'RES CHIP 0.0005 1W +-1%(1206)'               | 'CYN'   | 'RL1632T4F-0R5M-FN'   | 'EP(V1)'     | ''        | 'DISCRETE' | ''      | 'S5B-JEFF'      | 'CYN_RL1632T4F-0R5M-FN.pdf'             | ''                         | ''             | ''  | ''         | ''      | ''     | '20150930'  
 '0.005'   | '1%'      | '1W'    | 'SMLF'    | 'CHIP'   | 'SP_CS+0058FR02'(!) = 'Non-Preferred' | 'End of Life'      | 'CS+0058FR02' |'R2512A_4P_EOL'| 'RES CHIP 0.005 1W +-1%(2512)AEC'             | 'DAL'   | 'WSL25125L000FEA'     | 'EP(V1)'     | ''        | 'DISCRETE' | ''      | 'T2HV-JOHN'     | 'R2512A&4P&R2512_4PXF.doc'              | ''                         | ''             | ''  | ''         | ''      | ''     | '20151229'  
 '0.005'   | '1%'      | '1W'    | 'SMLF'    | 'EMPTY'  | 'SP_CS+0058FR02'(!) = 'Non-Preferred' | 'End of Life'      | 'CS+0058FR02' |'R2512A_4P_EOL'| 'RES CHIP 0.005 1W +-1%(2512)AEC'             | 'DAL'   | 'WSL25125L000FEA'     | 'EP(V1)'     | ''        | 'DISCRETE' | ''      | 'T2HV-JOHN'     | 'R2512A&4P&R2512_4PXF.doc'              | ''                         | ''             | ''  | ''         | ''      | ''     | '20151229'  
 '0.001'   | '1%'      | '1W'    | 'SMLF'    | 'CHIP'   | 'SP_CS+0018FR03'(!) = ''              | ''                 | 'CS+0018FR03' |'R2512A_4P'| 'RES CHIP 0.001 1W +-1%(2512)AEC'             | 'DAL'   | 'WSL25121L000FEA'     | 'EP(V1)'     | ''        | 'DISCRETE' | ''      | 'T2HV-JOHN'     | 'R2512A&4P&R2512_4PXF.doc'              | ''                         | ''             | ''  | ''         | ''      | ''     | '20151229'  
 '0.001'   | '1%'      | '1W'    | 'SMLF'    | 'EMPTY'  | 'SP_CS+0018FR03'(!) = ''              | ''                 | 'CS+0018FR03' |'R2512A_4P'| 'RES CHIP 0.001 1W +-1%(2512)AEC'             | 'DAL'   | 'WSL25121L000FEA'     | 'EP(V1)'     | ''        | 'DISCRETE' | ''      | 'T2HV-JOHN'     | 'R2512A&4P&R2512_4PXF.doc'              | ''                         | ''             | ''  | ''         | ''      | ''     | '20151229'  
 '0.0005'  | '1%'      | '1W'    | 'SMLF'    | 'CHIP'   | 'SP_CS00008FR03'(!) = ''              | ''                 | 'CS00008FR03' |'R2512A_4P'| 'RES CHIP 0.0005 1W +-1%(2512)AEC'            | 'DAL'   | 'WSL2512L5000FEA'     | 'EP(V1)'     | ''        | 'DISCRETE' | ''      | 'T2HV-JOHN'     | 'DAL_WSL2512L5000FEA.pdf'               | 'R2512A&4P&R2512_4PXF.doc' | ''             | ''  | ''         | ''      | ''     | '20160105'  
 '0.0005'  | '1%'      | '1W'    | 'SMLF'    | 'EMPTY'  | 'SP_CS00008FR03'(!) = ''              | ''                 | 'CS00008FR03' |'R2512A_4P'| 'RES CHIP 0.0005 1W +-1%(2512)AEC'            | 'DAL'   | 'WSL2512L5000FEA'     | 'EP(V1)'     | ''        | 'DISCRETE' | ''      | 'T2HV-JOHN'     | 'DAL_WSL2512L5000FEA.pdf'               | 'R2512A&4P&R2512_4PXF.doc' | ''             | ''  | ''         | ''      | ''     | '20160105'  
 '0.0003'  | '1%'      | '4W'    | 'SMLF'    | 'CHIP'   | 'SP_CS0000FFT04'(!) = 'End of Design' | 'Comp-Approve'     | 'CS0000FFT04' |'R2725_4P'| 'RES CHIP 0.0003 4W +-1%(2725)'               | 'RLC'   | 'LR2725-24R0003F1'    | 'EP(V1)'     | 'EP(V1)'  | 'DISCRETE' | ''      | 'S2VM-HANK'     | 'RLC_LR2725-24R0003F1.pdf'              | ''                         | ''             | ''  | ''         | ''      | ''     | '20160201'  
 '0.0003'  | '1%'      | '4W'    | 'SMLF'    | 'EMPTY'  | 'SP_CS0000FFT04'(!) = 'End of Design' | 'Comp-Approve'     | 'CS0000FFT04' |'R2725_4P'| 'RES CHIP 0.0003 4W +-1%(2725)'               | 'RLC'   | 'LR2725-24R0003F1'    | 'EP(V1)'     | 'EP(V1)'  | 'DISCRETE' | ''      | 'S2VM-HANK'     | 'RLC_LR2725-24R0003F1.pdf'              | ''                         | ''             | ''  | ''         | ''      | ''     | '20160201'  
 '0.002'   | '1%'      | '1W'    | 'SMLF'    | 'CHIP'   | 'SP_CS+0028F201'(!) = ''              | ''                 | 'CS+0028F201' |'R1206XA_4P'| 'RES CHIP 0.002 1W +-1%(1206)'                | 'RLC'   | 'LR1206-21R002F4'     | 'EP(V1)'     | 'EP(V1)'  | 'DISCRETE' | ''      | 'S5B-JOSHUA'    | 'RLC_LR1206-21R002F4.pdf'               | ''                         | ''             | ''  | ''         | ''      | ''     | '20160307'  
 '0.002'   | '1%'      | '1W'    | 'SMLF'    | 'EMPTY'  | 'SP_CS+0028F201'(!) = ''              | ''                 | 'CS+0028F201' |'R1206XA_4P'| 'RES CHIP 0.002 1W +-1%(1206)'                | 'RLC'   | 'LR1206-21R002F4'     | 'EP(V1)'     | 'EP(V1)'  | 'DISCRETE' | ''      | 'S5B-JOSHUA'    | 'RLC_LR1206-21R002F4.pdf'               | ''                         | ''             | ''  | ''         | ''      | ''     | '20160307'  
 '0.003'   | '1%'      | '2W'    | 'SMLF'    | 'CHIP'   | 'SP_CS+003AFR00_1'(!) = ''              | ''                 | 'CS+003AFR00' |'R2512_4PXM'| 'RES CHIP 0.003 2W +-1%(2512)'                | 'YGO'   | 'PR2512FKF7W0R003L'   | 'EP(V1)'     | 'EP(V1)'  | 'DISCRETE' | ''      | 'G1A-AI-JU'     | 'YGO_Cur SensorRes_20130301.pdf'        | ''                         | ''             | ''  | ''         | ''      | ''     | '20160606'  
 '0.003'   | '1%'      | '2W'    | 'SMLF'    | 'EMPTY'  | 'SP_CS+003AFR00_1'(!) = ''              | ''                 | 'CS+003AFR00' |'R2512_4PXM'| 'RES CHIP 0.003 2W +-1%(2512)'                | 'YGO'   | 'PR2512FKF7W0R003L'   | 'EP(V1)'     | 'EP(V1)'  | 'DISCRETE' | ''      | 'G1A-AI-JU'     | 'YGO_Cur SensorRes_20130301.pdf'        | ''                         | ''             | ''  | ''         | ''      | ''     | '20160606'  
 '0.0005'  | '1%'      | '1W'    | 'SMLF'    | 'CHIP'   | 'CS00008FP10'(!)   = 'Non-Preferred' | 'End of Life'      | 'CS00008FP10' |'R0612_4P_EOL'| 'RES CHIP 0.0005 1W +-1%(0612)DAL AEC'        | 'DAL'   | 'WSK0612L5000FEA'     | 'EP(V1)'     | ''        | 'DISCRETE' | ''      | 'T2HV-MARK'     | 'DAL_WSK0612L5000FEA.pdf'               | ''                         | ''             | ''  | ''         | ''      | ''     | '20160722'  
 '0.0005'  | '1%'      | '1W'    | 'SMLF'    | 'EMPTY'  | 'CS00008FP10'(!)   = 'Non-Preferred' | 'End of Life'      | 'CS00008FP10' |'R0612_4P_EOL'| 'RES CHIP 0.0005 1W +-1%(0612)DAL AEC'        | 'DAL'   | 'WSK0612L5000FEA'     | 'EP(V1)'     | ''        | 'DISCRETE' | ''      | 'T2HV-MARK'     | 'DAL_WSK0612L5000FEA.pdf'               | ''                         | ''             | ''  | ''         | ''      | ''     | '20160722'  
 '0.0002'  | '1%'      | '9W'    | 'SMLF'    | 'CHIP'   | 'SP_CS0000KFY00'(!) = ''              | ''                 | 'CS0000KFY00' |'R3921_4P'| 'RES CHIP 0.0002 9W +-1%(3921)DAL_AEC'        | 'DAL'   | 'WSLP3921L2000FEA'    | 'EP(V1)'     | ''        | 'DISCRETE' | ''      | 'T2HV-MARK'     | 'DAL_WSLP3921L2000FEA.pdf'              | ''                         | ''             | ''  | ''         | ''      | ''     | '20160725'  
 '0.0002'  | '1%'      | '9W'    | 'SMLF'    | 'EMPTY'  | 'SP_CS0000KFY00'(!) = ''              | ''                 | 'CS0000KFY00' |'R3921_4P'| 'RES CHIP 0.0002 9W +-1%(3921)DAL_AEC'        | 'DAL'   | 'WSLP3921L2000FEA'    | 'EP(V1)'     | ''        | 'DISCRETE' | ''      | 'T2HV-MARK'     | 'DAL_WSLP3921L2000FEA.pdf'              | ''                         | ''             | ''  | ''         | ''      | ''     | '20160725'  
 '0.001'   | '1%'      | '3W'    | 'SMLF'    | 'CHIP'   | 'SP_CS+001DFR00_1'(!) = ''              | ''                 | 'CS+001DFR00' |'R2512_4PXN'| 'RES CHIP 0.001 3W(+-1%,2512)'                | 'RLC'   | 'LR2512-23R001F4'     | 'EU(V1)'     | ''        | 'DISCRETE' | ''      | 'S5B-HANK'      | 'RLC_LR2512-23R001F4_2015.07.01.pdf'    | ''                         | ''             | ''  | ''         | ''      | ''     | '20160809'  
 '0.001'   | '1%'      | '3W'    | 'SMLF'    | 'EMPTY'  | 'SP_CS+001DFR00_1'(!) = ''              | ''                 | 'CS+001DFR00' |'R2512_4PXN'| 'RES CHIP 0.001 3W(+-1%,2512)'                | 'RLC'   | 'LR2512-23R001F4'     | 'EU(V1)'     | ''        | 'DISCRETE' | ''      | 'S5B-HANK'      | 'RLC_LR2512-23R001F4_2015.07.01.pdf'    | ''                         | ''             | ''  | ''         | ''      | ''     | '20160809'  
 '0.001'   | '1%'      | '2W'    | 'SMLF'    | 'CHIP'   | 'SP_CS+001AFR03'(!) = ''              | ''                 | 'CS+001AFR03' |'R2512_4PXH'| 'RES CHIP 0.001 2W +-1%(2512)'                | 'RLC'   | 'LR2512-22R001F4'     | 'EP(V1)'     | ''        | 'DISCRETE' | ''      | 'JBW-KENNETH'   | 'RLC-LR2512-22R001F4_20160708.pdf'      | ''                         | ''             | ''  | ''         | ''      | ''     | '20161007'  
 '0.001'   | '1%'      | '2W'    | 'SMLF'    | 'EMPTY'  | 'SP_CS+001AFR03'(!) = ''              | ''                 | 'CS+001AFR03' |'R2512_4PXH'| 'RES CHIP 0.001 2W +-1%(2512)'                | 'RLC'   | 'LR2512-22R001F4'     | 'EP(V1)'     | ''        | 'DISCRETE' | ''      | 'JBW-KENNETH'   | 'RLC-LR2512-22R001F4_20160708.pdf'      | ''                         | ''             | ''  | ''         | ''      | ''     | '20161007'  
 '0.001'   | '1%'      | '1W'    | 'SMLF'    | 'CHIP'   | 'SP_CS+0018F200'(!) = ''              | ''                 | 'CS+0018F200' |'R1206XA_4P'| 'RES CHIP 0.001 1W +-1%(1206)'                | 'RLC'   | 'LR1206-21R001F4'     | 'EP(V1)'     | ''        | 'DISCRETE' | ''      | 'S5S-HANK'      | 'RLC_LR1206-21R001F4.pdf'               | ''                         | ''             | ''  | ''         | ''      | ''     | '20161118'  
 '0.001'   | '1%'      | '1W'    | 'SMLF'    | 'EMPTY'  | 'SP_CS+0018F200'(!) = ''              | ''                 | 'CS+0018F200' |'R1206XA_4P'| 'RES CHIP 0.001 1W +-1%(1206)'                | 'RLC'   | 'LR1206-21R001F4'     | 'EP(V1)'     | ''        | 'DISCRETE' | ''      | 'S5S-HANK'      | 'RLC_LR1206-21R001F4.pdf'               | ''                         | ''             | ''  | ''         | ''      | ''     | '20161118'  
 '0.01'    | '1%'      | '1/2W'  | 'SMLF'    | 'CHIP'   | 'SP_CS+0107F211'(!) = ''              | ''                 | 'CS+0107F211' |'R1206XG_4P'| 'RES CHIP 0.01 1/2W +-1%(1206)'               | 'CYN'   | 'RL1632H-R010-FN'     | 'EP(V1)'     | 'EP(V1)'  | 'DISCRETE' | ''      | 'JB7T-JOSHUA'   | 'CYN_LF_RL SERIES.pdf'                  | ''                         | ''             | ''  | ''         | ''      | ''     | '2017213'   
 '0.01'    | '1%'      | '1/2W'  | 'SMLF'    | 'EMPTY'  | 'SP_CS+0107F211'(!) = ''              | ''                 | 'CS+0107F211' |'R1206XG_4P'| 'RES CHIP 0.01 1/2W +-1%(1206)'               | 'CYN'   | 'RL1632H-R010-FN'     | 'EP(V1)'     | 'EP(V1)'  | 'DISCRETE' | ''      | 'JB7T-JOSHUA'   | 'CYN_LF_RL SERIES.pdf'                  | ''                         | ''             | ''  | ''         | ''      | ''     | '2017213'   
 '0.01'    | '1%'      | '1W'    | 'SMLF'    | 'CHIP'   | 'SP_CS+0108FL09'(!) = ''              | ''                 | 'CS+0108FL09' |'R3720XA_4P'| 'RESISTOR CHIP 0.01 1W +-1%(3720)'            | 'CYN'   | 'RL3720WT-R010-FN'    | 'EP(V1)'     | 'EP(V1)'  | 'DISCRETE' | ''      | 'JB7T-JOSHUA'   | 'R3720XA.dra'                           | ''                         | ''             | ''  | ''         | ''      | ''     | '20170216'  
 '0.01'    | '1%'      | '1W'    | 'SMLF'    | 'EMPTY'  | 'SP_CS+0108FL09'(!) = ''              | ''                 | 'CS+0108FL09' |'R3720XA_4P'| 'RESISTOR CHIP 0.01 1W +-1%(3720)'            | 'CYN'   | 'RL3720WT-R010-FN'    | 'EP(V1)'     | 'EP(V1)'  | 'DISCRETE' | ''      | 'JB7T-JOSHUA'   | 'R3720XA.dra'                           | ''                         | ''             | ''  | ''         | ''      | ''     | '20170216'  
 '0.0005'  | '1%'      | '3W'    | 'SMLF'    | 'CHIP'   | 'SP_CS0000DFR05'(!) = ''              | ''                 | 'CS0000DFR05' |'R2512XO_4P'| 'RES CHIP 0.0005 3W +-1%(2512)CYN'            | 'CYN'   | 'RLD-3264-0F-0R5M-FN' | 'EP(V1)'     | ''        | 'DISCRETE' | ''      | 'JBW-KENNETH'   | 'CYN_RLD-3264-0F-0R5M-FN.pdf'           | ''                         | ''             | ''  | ''         | ''      | ''     | '20170607'  
 '0.0005'  | '1%'      | '3W'    | 'SMLF'    | 'EMPTY'  | 'SP_CS0000DFR05'(!) = ''              | ''                 | 'CS0000DFR05' |'R2512XO_4P'| 'RES CHIP 0.0005 3W +-1%(2512)CYN'            | 'CYN'   | 'RLD-3264-0F-0R5M-FN' | 'EP(V1)'     | ''        | 'DISCRETE' | ''      | 'JBW-KENNETH'   | 'CYN_RLD-3264-0F-0R5M-FN.pdf'           | ''                         | ''             | ''  | ''         | ''      | ''     | '20170607'  
 '0.001'   | '1%'      | '1W'    | 'SMLF'    | 'CHIP'   | 'SP_CS+0018FR05_1'(!) = ''              | ''                 | 'CS+0018FR05' |'R2512XF_4P'| 'RES CHIP 0.001(+-1%,1W, 2512)TAI_4P'         | 'TAI'   | 'RLM25FECR001'        | 'EP(V1)'     | 'EP(V1)'  | 'DISCRETE' | ''      | 'F0B-HANK'      | 'TAI_RLM25FECR001.pdf'                  | ''                         | ''             | ''  | ''         | ''      | ''     | '20180302'  
 '0.001'   | '1%'      | '1W'    | 'SMLF'    | 'EMPTY'  | 'SP_CS+0018FR05_1'(!) = ''              | ''                 | 'CS+0018FR05' |'R2512XF_4P'| 'RES CHIP 0.001(+-1%,1W, 2512)TAI_4P'         | 'TAI'   | 'RLM25FECR001'        | 'EP(V1)'     | 'EP(V1)'  | 'DISCRETE' | ''      | 'F0B-HANK'      | 'TAI_RLM25FECR001.pdf'                  | ''                         | ''             | ''  | ''         | ''      | ''     | '20180302'  
 '0.006'   | '1%'      | '1W'    | 'SMLF'    | 'CHIP'   | 'SP_CS+0068F200'(!) = ''              | ''                 | 'CS+0068F200' |'R1206XI_H18_4P'| 'RES CHIP 0.006 1W +-1%(1206)EF_4P'           | 'WTC'   | 'WW12RR006FTL'        | 'EP(V1)'     | ''        | 'DISCRETE' | ''      | 'JG5-DAN'       | 'WTC_WW12RR006FTL.pdf'                  | ''                         | ''             | ''  | ''         | ''      | ''     | '20180514'  
 '0.006'   | '1%'      | '1W'    | 'SMLF'    | 'EMPTY'  | 'SP_CS+0068F200'(!) = ''              | ''                 | 'CS+0068F200' |'R1206XI_H18_4P'| 'RES CHIP 0.006 1W +-1%(1206)EF_4P'           | 'WTC'   | 'WW12RR006FTL'        | 'EP(V1)'     | ''        | 'DISCRETE' | ''      | 'JG5-DAN'       | 'WTC_WW12RR006FTL.pdf'                  | ''                         | ''             | ''  | ''         | ''      | ''     | '20180514'  
 '0.0003'  | '1%'      | '3W'    | 'SMLF'    | 'CHIP'   | 'SP_CS0000DFR03_1'(!) = 'End of Design' | 'Comp-Approve'     | 'CS0000DFR03' |'R2512A_4P_H57'| 'RES CHIP 0.0003 3W +-1%(2512)_4P'            | 'RLC'   | 'LR2512-23R0003F1'    | 'EP(V1)'     | 'EP(V1)'  | 'DISCRETE' | ''      | 'T2C-CARLOS'    | 'R2512_6PXA.pdf'                        | ''                         | ''             | ''  | ''         | ''      | ''     | '20180525'  
 '0.0003'  | '1%'      | '3W'    | 'SMLF'    | 'EMPTY'  | 'SP_CS0000DFR03_1'(!) = 'End of Design' | 'Comp-Approve'     | 'CS0000DFR03' |'R2512A_4P_H57'| 'RES CHIP 0.0003 3W +-1%(2512)_4P'            | 'RLC'   | 'LR2512-23R0003F1'    | 'EP(V1)'     | 'EP(V1)'  | 'DISCRETE' | ''      | 'T2C-CARLOS'    | 'R2512_6PXA.pdf'                        | ''                         | ''             | ''  | ''         | ''      | ''     | '20180525'  
 '0.01'    | '1%'      | '3W'    | 'SMLF'    | 'CHIP'   | 'SP_CS+100DFR00_1'(!) = ''              | ''                 | 'CS+100DFR00' |'R2512XA_4P'| 'RES CHIP 0.01 3W +-1%(2512)'                 | 'TAI'   | 'RLP25FEGR010'        | 'EP(V1)'     | 'EP(V1)'  | 'DISCRETE' | ''      | 'A7N-MIKE'      | 'TAI_LF_RM SERIES-4.pdf'                | 'R2512XA.doc'              | ''             | ''  | ''         | ''      | ''     | '20181024'  
 '0.01'    | '1%'      | '3W'    | 'SMLF'    | 'EMPTY'  | 'SP_CS+100DFR00_1'(!) = ''              | ''                 | 'CS+100DFR00' |'R2512XA_4P'| 'RES CHIP 0.01 3W +-1%(2512)'                 | 'TAI'   | 'RLP25FEGR010'        | 'EP(V1)'     | 'EP(V1)'  | 'DISCRETE' | ''      | 'A7N-MIKE'      | 'TAI_LF_RM SERIES-4.pdf'                | 'R2512XA.doc'              | ''             | ''  | ''         | ''      | ''     | '20181024'  
 '0.005'   | '1%'      | '1W'    | 'SMLF'    | 'CHIP'   | 'SP_CS+0058F200'(!) = ''              | ''                 | 'CS+0058F200' |'R1206XK_4P'| 'RES CHIP  0.005  1W +-1%(1206)'              | 'TAI'   | 'RLM12FTCMR005'       | 'EP(V1)'     | 'EP(V1)'  | 'DISCRETE' | ''      | 'JG5-TOM'       | 'TAI_RLM12FTCMR005.pdf'                 | ''                         | ''             | ''  | ''         | ''      | ''     | '20181113'  
 '0.005'   | '1%'      | '1W'    | 'SMLF'    | 'EMPTY'  | 'SP_CS+0058F200'(!) = ''              | ''                 | 'CS+0058F200' |'R1206XK_4P'| 'RES CHIP  0.005  1W +-1%(1206)'              | 'TAI'   | 'RLM12FTCMR005'       | 'EP(V1)'     | 'EP(V1)'  | 'DISCRETE' | ''      | 'JG5-TOM'       | 'TAI_RLM12FTCMR005.pdf'                 | ''                         | ''             | ''  | ''         | ''      | ''     | '20181113'  
 '0.002'   | '1%'      | '1W'    | 'SMLF'    | 'CHIP'   | 'CS+0028FP06'(!)   = 'End of Design' | 'Comp-Release Qty' | 'CS+0028FP06' |'R1206_4P'| 'RES CHIP 0.002 1W +-1%(0612)C-S EF'          | 'CYN'   | 'RL1632T4F-R002-FN'   | 'EP(V1)'     | ''        | 'DISCRETE' | ''      | 'PACIFICA-SAM'  | 'CYN_RL1632T4F-R002-FN.pdf'             | ''                         | ''             | ''  | ''         | ''      | ''     | '20181212'  
 '0.002'   | '1%'      | '1W'    | 'SMLF'    | 'EMPTY'  | 'CS+0028FP06'(!)   = 'End of Design' | 'Comp-Release Qty' | 'CS+0028FP06' |'R1206_4P'| 'RES CHIP 0.002 1W +-1%(0612)C-S EF'          | 'CYN'   | 'RL1632T4F-R002-FN'   | 'EP(V1)'     | ''        | 'DISCRETE' | ''      | 'PACIFICA-SAM'  | 'CYN_RL1632T4F-R002-FN.pdf'             | ''                         | ''             | ''  | ''         | ''      | ''     | '20181212'  
 '0.0005'  | '1%'      | '1W'    | 'SMLF'    | 'CHIP'   | 'CS00008FP11'(!)   = 'End of Design' | 'P/N Release'      | 'CS00008FP11' |'R1206_4P'| 'RES CHIP 0.0005 1W +-1%(0612)C-S EF'         | 'CYN'   | 'RL1632T4F-0R5M-FN'   | 'EP(V1)'     | 'EP(V1)'  | 'DISCRETE' | ''      | 'PACIFICA-SAM'  | 'CYN_RL1632T4F-0R5M-FN_CS00008FP11.pdf' | ''                         | ''             | ''  | ''         | ''      | ''     | '20181212'  
 '0.0005'  | '1%'      | '1W'    | 'SMLF'    | 'EMPTY'  | 'CS00008FP11'(!)   = 'End of Design' | 'P/N Release'      | 'CS00008FP11' |'R1206_4P'| 'RES CHIP 0.0005 1W +-1%(0612)C-S EF'         | 'CYN'   | 'RL1632T4F-0R5M-FN'   | 'EP(V1)'     | 'EP(V1)'  | 'DISCRETE' | ''      | 'PACIFICA-SAM'  | 'CYN_RL1632T4F-0R5M-FN_CS00008FP11.pdf' | ''                         | ''             | ''  | ''         | ''      | ''     | '20181212'  
 '0.003'   | '1%'      | '1W'    | 'SMLF'    | 'CHIP'   | 'SP_CS+0038F203'(!) = ''              | ''                 | 'CS+0038F203' |'R1206XK_4P'| 'RES CHIP 0.003 1W +-1%(1206)'                | 'TAI'   | 'RLM12FTCMR003'       | 'EP(V1)'     | ''        | 'DISCRETE' | ''      | 'T2C-LEO'       | 'TAI_RLM12FTCMR003.pdf'                 | ''                         | ''             | ''  | ''         | ''      | ''     | '20190904'  
 '0.003'   | '1%'      | '1W'    | 'SMLF'    | 'EMPTY'  | 'SP_CS+0038F203'(!) = ''              | ''                 | 'CS+0038F203' |'R1206XK_4P'| 'RES CHIP 0.003 1W +-1%(1206)'                | 'TAI'   | 'RLM12FTCMR003'       | 'EP(V1)'     | ''        | 'DISCRETE' | ''      | 'T2C-LEO'       | 'TAI_RLM12FTCMR003.pdf'                 | ''                         | ''             | ''  | ''         | ''      | ''     | '20190904'  
 '0.0006'  | '1%'      | '4W'    | 'SMLF'    | 'CHIP'   | 'SP_CS0000FFT03'(!) = 'End of Design' | 'Comp-Approve'     | 'CS0000FFT03' |'R2725_4P'| 'RES CHIP 0.0006 4W +-1%(2725)H0.991'         | 'RLC'   | 'LR2725-24R0006F1'    | 'EP(V1)'     | 'EP(V1)'  | 'DISCRETE' | ''      | 'F0D-FRANK'     | 'RLC_LR2725-24R0006F1.pdf'              | ''                         | ''             | ''  | ''         | ''      | ''     | '20191204'  
 '0.0006'  | '1%'      | '4W'    | 'SMLF'    | 'EMPTY'  | 'SP_CS0000FFT03'(!) = 'End of Design' | 'Comp-Approve'     | 'CS0000FFT03' |'R2725_4P'| 'RES CHIP 0.0006 4W +-1%(2725)H0.991'         | 'RLC'   | 'LR2725-24R0006F1'    | 'EP(V1)'     | 'EP(V1)'  | 'DISCRETE' | ''      | 'F0D-FRANK'     | 'RLC_LR2725-24R0006F1.pdf'              | ''                         | ''             | ''  | ''         | ''      | ''     | '20191204'  
 '0.0004'  | '1%'      | '4W'    | 'SMLF'    | 'CHIP'   | 'SP_CS0000FFT08'(!) = 'End of Design' | 'Comp-Release Qty' | 'CS0000FFT08' |'R2725_4P'| 'RES CHIP 0.0004 4W +-1%(2725)'               | 'RLC'   | 'LR2725-24R0004F1'    | 'EP(V1)'     | ''        | 'DISCRETE' | ''      | 'F0D-FRANK'     | 'RLC_LR2725-24R0004F1.pdf'              | ''                         | ''             | ''  | ''         | ''      | ''     | '20191227'  
 '0.0004'  | '1%'      | '4W'    | 'SMLF'    | 'EMPTY'  | 'SP_CS0000FFT08'(!) = 'End of Design' | 'Comp-Release Qty' | 'CS0000FFT08' |'R2725_4P'| 'RES CHIP 0.0004 4W +-1%(2725)'               | 'RLC'   | 'LR2725-24R0004F1'    | 'EP(V1)'     | ''        | 'DISCRETE' | ''      | 'F0D-FRANK'     | 'RLC_LR2725-24R0004F1.pdf'              | ''                         | ''             | ''  | ''         | ''      | ''     | '20191227'  
 '0.0003'  | '1%'      | '8W'    | 'SMLF'    | 'CHIP'   | 'SP_CS0000LFR00'(!) = ''              | ''                 | 'CS0000LFR00' |'R2512XV_4P_SHORT'| 'RES CHIP 0.0003 8W +-1% (2512)KOA'           | 'KOA'   | 'PSL2NTEBL300F'       | 'EP(V1)'     | ''        | 'DISCRETE' | ''      | 'S8A-KENNY'     | 'KOA_PSL2NTEBL300F.pdf'                 | ''                         | ''             | ''  | ''         | ''      | ''     | '20200227'  
 '0.0003'  | '1%'      | '8W'    | 'SMLF'    | 'EMPTY'  | 'SP_CS0000LFR00'(!) = ''              | ''                 | 'CS0000LFR00' |'R2512XV_4P_SHORT'| 'RES CHIP 0.0003 8W +-1% (2512)KOA'           | 'KOA'   | 'PSL2NTEBL300F'       | 'EP(V1)'     | ''        | 'DISCRETE' | ''      | 'S8A-KENNY'     | 'KOA_PSL2NTEBL300F.pdf'                 | ''                         | ''             | ''  | ''         | ''      | ''     | '20200227'  
 '0.01'    | '1%'      | '1W'    | 'SMLF'    | 'CHIP'   | 'SP_CS+0108F207'(!) = ''              | ''                 | 'CS+0108F207' |'R1206XO_4P_SHORT'| 'RES CHIP 0.01 1W +-1%(1206)EF'               | 'WTC'   | 'WW12NR010FTL'        | 'EP(V1)'     | 'EP(V1)'  | 'DISCRETE' | ''      | 'F0E-WILLIAM'   | 'WTC_WW12NR010FTL.pdf'                  | ''                         | ''             | ''  | ''         | ''      | ''     | '20200604'  
 '0.01'    | '1%'      | '1W'    | 'SMLF'    | 'EMPTY'  | 'SP_CS+0108F207'(!) = ''              | ''                 | 'CS+0108F207' |'R1206XO_4P_SHORT'| 'RES CHIP 0.01 1W +-1%(1206)EF'               | 'WTC'   | 'WW12NR010FTL'        | 'EP(V1)'     | 'EP(V1)'  | 'DISCRETE' | ''      | 'F0E-WILLIAM'   | 'WTC_WW12NR010FTL.pdf'                  | ''                         | ''             | ''  | ''         | ''      | ''     | '20200604'  
 '0.0003'  | '1%'      | '4W'    | 'SMLF'    | 'CHIP'   | 'SP_CS0000FFT09'(!) = ''              | ''                 | 'CS0000FFT09' |'R2725_4P'| 'RES CHIP 0.0003 4W +-1%(2725)RLC'            | 'RLC'   | 'LR2725-24R0003F1'    | 'EP(V1)'     | 'EP(V1)'  | 'DISCRETE' | ''      | 'IOX-EGBERT'    | 'RLC_LR2725-24R0003F1.pdf'              | ''                         | ''             | ''  | ''         | ''      | ''     | '20200617'  
 '0.0003'  | '1%'      | '4W'    | 'SMLF'    | 'EMPTY'  | 'SP_CS0000FFT09'(!) = ''              | ''                 | 'CS0000FFT09' |'R2725_4P'| 'RES CHIP 0.0003 4W +-1%(2725)RLC'            | 'RLC'   | 'LR2725-24R0003F1'    | 'EP(V1)'     | 'EP(V1)'  | 'DISCRETE' | ''      | 'IOX-EGBERT'    | 'RLC_LR2725-24R0003F1.pdf'              | ''                         | ''             | ''  | ''         | ''      | ''     | '20200617'  
 '0.0003'  | '1%'      | '4W'    | 'SMLF'    | 'CHIP'   | 'SP_CS0000FFT10'(!) = 'End of Design' | 'Comp-Approve'     | 'CS0000FFT10' |'R2725XA_4P_SHORT'| 'RES CHIP 0.0003 4W +-1%(2725)ERO'            | 'ERO'   | 'MA272540F0M30SZ'     | 'EP(V1)'     | ''        | 'DISCRETE' | ''      | 'IOX-EGBERT'    | 'ERO_MA272540F0M30SZ.pdf'               | ''                         | ''             | ''  | ''         | ''      | ''     | '20200622'  
 '0.0003'  | '1%'      | '4W'    | 'SMLF'    | 'EMPTY'  | 'SP_CS0000FFT10'(!) = 'End of Design' | 'Comp-Approve'     | 'CS0000FFT10' |'R2725XA_4P_SHORT'| 'RES CHIP 0.0003 4W +-1%(2725)ERO'            | 'ERO'   | 'MA272540F0M30SZ'     | 'EP(V1)'     | ''        | 'DISCRETE' | ''      | 'IOX-EGBERT'    | 'ERO_MA272540F0M30SZ.pdf'               | ''                         | ''             | ''  | ''         | ''      | ''     | '20200622'  
 '0.0005'  | '1%'      | '3W'    | 'SMLF'    | 'CHIP'   | 'SP_CS0000DFR02'(!) = 'End of Design' | 'Comp-Approve'     | 'CS0000DFR02' |'R2512_4PXH'| 'RES CHIP 0.0005 3W +-1%(2512)EF'             | 'YGO'   | 'PR2512FKE7T0U5Z'     | 'EP(V1)'     | 'EP(V1)'  | 'DISCRETE' | ''      | 'F0CE-GUAN-XUN' | 'YGO_PR2512FKE7T0U5Z.pdf'               | ''                         | ''             | ''  | ''         | ''      | ''     | '20200903'  
 '0.0005'  | '1%'      | '3W'    | 'SMLF'    | 'EMPTY'  | 'SP_CS0000DFR02'(!) = 'End of Design' | 'Comp-Approve'     | 'CS0000DFR02' |'R2512_4PXH'| 'RES CHIP 0.0005 3W +-1%(2512)EF'             | 'YGO'   | 'PR2512FKE7T0U5Z'     | 'EP(V1)'     | 'EP(V1)'  | 'DISCRETE' | ''      | 'F0CE-GUAN-XUN' | 'YGO_PR2512FKE7T0U5Z.pdf'               | ''                         | ''             | ''  | ''         | ''      | ''     | '20200903'  
 '0.0005'  | '1%'      | '3W'    | 'SMLF'    | 'CHIP'   | 'SP_CS0000DFR17'(!) = ''              | ''                 | 'CS0000DFR17' |'R2512XX_4P_SHORT'| 'RES CHIP 0.0005 3W +-1%(2512)ERO_4P'         | 'ERO'   | 'MA251230F0M50SZ'     | 'EP(V1)'     | ''        | 'DISCRETE' | ''      | 'S6Q-KIMI'      | 'ERO_MA251230F0M50SZ.pdf'               | 'MA251230F0M50SZ.msg'      | ''             | ''  | ''         | ''      | ''     | '20200917'  
 '0.0005'  | '1%'      | '3W'    | 'SMLF'    | 'EMPTY'  | 'SP_CS0000DFR17'(!) = ''              | ''                 | 'CS0000DFR17' |'R2512XX_4P_SHORT'| 'RES CHIP 0.0005 3W +-1%(2512)ERO_4P'         | 'ERO'   | 'MA251230F0M50SZ'     | 'EP(V1)'     | ''        | 'DISCRETE' | ''      | 'S6Q-KIMI'      | 'ERO_MA251230F0M50SZ.pdf'               | 'MA251230F0M50SZ.msg'      | ''             | ''  | ''         | ''      | ''     | '20200917'  
 '0.0002'  | '1%'      | '4W'    | 'SMLF'    | 'CHIP'   | 'SP_CS0000FFT11'(!) = ''              | ''                 | 'CS0000FFT11' |'R2725_4P'| 'RES CHIP 0.0002 4W +-1%(2725)RLC_4P'         | 'RLC'   | 'LR2725-24R0002F1'    | 'EP(V1)'     | 'EP(V1)'  | 'DISCRETE' | ''      | 'T6G-HARRY'     | 'RLC_LR2725-24R0002F1.pdf'              | 'LR2725-24R0002F1.msg'     | ''             | ''  | ''         | ''      | ''     | '20210819'  
 '0.0002'  | '1%'      | '4W'    | 'SMLF'    | 'EMPTY'  | 'SP_CS0000FFT11'(!) = ''              | ''                 | 'CS0000FFT11' |'R2725_4P'| 'RES CHIP 0.0002 4W +-1%(2725)RLC_4P'         | 'RLC'   | 'LR2725-24R0002F1'    | 'EP(V1)'     | 'EP(V1)'  | 'DISCRETE' | ''      | 'T6G-HARRY'     | 'RLC_LR2725-24R0002F1.pdf'              | 'LR2725-24R0002F1.msg'     | ''             | ''  | ''         | ''      | ''     | '20210819'  
 '0.015'   | '0.5%'    | '7W'    | 'SMLF'    | 'CHIP'   | 'SP_CS+015LDX00'(!) = ''              | ''                 | 'CS+015LDX00' |'R2818XA_4P'| 'RES CHIP 0.015 7W +-0.5%(2818)SIL AEC_4P'    | 'SIL'   | 'WSHM2818R0150DEA'    | 'EP(V1)'     | ''        | 'DISCRETE' | ''      | 'MF6-STEVEN'    | 'SIL_WSHM2818R0150DEA.pdf'              | 'WSHM2818R0150DEA.msg'     | ''             | ''  | ''         | ''      | ''     | '20230207'  
 '0.015'   | '0.5%'    | '7W'    | 'SMLF'    | 'EMPTY'  | 'SP_CS+015LDX00'(!) = ''              | ''                 | 'CS+015LDX00' |'R2818XA_4P'| 'RES CHIP 0.015 7W +-0.5%(2818)SIL AEC_4P'    | 'SIL'   | 'WSHM2818R0150DEA'    | 'EP(V1)'     | ''        | 'DISCRETE' | ''      | 'MF6-STEVEN'    | 'SIL_WSHM2818R0150DEA.pdf'              | 'WSHM2818R0150DEA.msg'     | ''             | ''  | ''         | ''      | ''     | '20230207'  

END_PART

END.

